#ISCELL
  pure_quanta quanta_title_block_c *
  *
#CELL
  pure_quanta q_cap *
  page76_i1
#CELL
  pure_quanta q_cap *
  page76_i10
#CELL
  pure_quanta q_cap *
  page76_i11
#ISCELL
  logical_power universal_power *
  page76_i12
#CELL
  pure_quanta q_cap *
  page76_i13
#CELL
  pure_quanta q_cap *
  page76_i14
#ISCELL
  logical_power universal_gnd *
  page76_i15
#CELL
  pure_quanta q_cap *
  page76_i16
#ISCELL
  logical_power universal_power *
  page76_i17
#CELL
  pure_quanta q_cap *
  page76_i18
#ISCELL
  logical_power universal_power *
  page76_i19
#CELL
  pure_quanta q_cap *
  page76_i2
#CELL
  pure_quanta q_cap *
  page76_i20
#CELL
  pure_quanta q_cap *
  page76_i21
#CELL
  pure_quanta q_cap *
  page76_i22
#CELL
  pure_quanta q_cap *
  page76_i23
#ISCELL
  logical_power universal_power *
  page76_i24
#CELL
  pure_quanta q_cap *
  page76_i25
#CELL
  pure_quanta q_cap *
  page76_i26
#CELL
  pure_quanta q_cap *
  page76_i27
#CELL
  pure_quanta q_cap *
  page76_i28
#CELL
  pure_quanta q_cap *
  page76_i29
#CELL
  pure_quanta q_cap *
  page76_i3
#ISCELL
  logical_power universal_gnd *
  page76_i30
#CELL
  pure_quanta q_cap *
  page76_i31
#CELL
  pure_quanta q_cap *
  page76_i32
#CELL
  pure_quanta q_cap *
  page76_i33
#ISCELL
  logical_power universal_gnd *
  page76_i34
#CELL
  pure_quanta q_cap *
  page76_i35
#CELL
  pure_quanta q_cap *
  page76_i36
#CELL
  pure_quanta q_cap *
  page76_i37
#CELL
  pure_quanta q_cap *
  page76_i38
#CELL
  pure_quanta q_cap *
  page76_i39
#ISCELL
  logical_power universal_power *
  page76_i4
#ISCELL
  logical_power universal_gnd *
  page76_i40
#CELL
  pure_quanta q_cap *
  page76_i41
#ISCELL
  logical_power universal_gnd *
  page76_i42
#CELL
  pure_quanta q_cap *
  page76_i43
#CELL
  pure_quanta q_cap *
  page76_i44
#CELL
  pure_quanta q_cap *
  page76_i45
#CELL
  pure_quanta q_cap *
  page76_i46
#CELL
  pure_quanta q_cap *
  page76_i47
#CELL
  pure_quanta q_cap *
  page76_i48
#CELL
  pure_quanta q_cap *
  page76_i49
#CELL
  pure_quanta q_cap *
  page76_i5
#CELL
  pure_quanta q_cap *
  page76_i50
#CELL
  pure_quanta q_cap *
  page76_i51
#CELL
  pure_quanta q_cap *
  page76_i52
#CELL
  pure_quanta q_cap *
  page76_i53
#CELL
  pure_quanta q_cap *
  page76_i54
#ISCELL
  logical_power universal_gnd *
  page76_i55
#CELL
  pure_quanta q_cap *
  page76_i6
#CELL
  pure_quanta q_cap *
  page76_i7
#ISCELL
  logical_power universal_power *
  page76_i8
#CELL
  pure_quanta q_cap *
  page76_i9
